# S9S_MB_2U (Grand Teton) — schematic netlist excerpt (pin names and nets, part order shuffled) for the footprints in the layout excerpt that follows; sources: Cadence DE-HDL packaged netlist, KiCad conversion of 03242023_DA0F0TMBIJ0_F0T_Motherboard_J_brd_V01_OCP.brd

R1018  Q_RES  0 5% CHIP  pkg 0402LF  page 209 : A = CLK_25M_CK440_CPU1_DN ; B = CLK_25M_CK440_CPU1_R_DN
PC2239  Q_CAP  2.2UF 16V 20% X7R  pkg C0603  page 242 : A = P12V_SCM_AVIN_PD ; B = GND

(kicad_pcb
	(version 20260206)
	(generator "pcbnew")
	(generator_version "10.0")
	(general
		(thickness 1.6)
		(legacy_teardrops no)
	)
	(paper "A4")
	(title_block
		(title "03242023_DA0F0TMBIJ0_F0T_Motherboard_J_brd_V01_OCP.brd")
		(comment 1 "Grand Teton / footprints 1206-1207 of 6105")
	)
	(layers
		(0 "F.Cu" signal "TOP")
		(4 "In1.Cu" signal "GND")
		(6 "In2.Cu" signal "IN1")
		(8 "In3.Cu" signal "GND1")
		(10 "In4.Cu" signal "IN2")
		(12 "In5.Cu" signal "GND2")
		(14 "In6.Cu" signal "IN3")
		(16 "In7.Cu" signal "GND3")
		(18 "In8.Cu" signal "VCC")
		(20 "In9.Cu" signal "VCC1")
		(22 "In10.Cu" signal "GND4")
		(24 "In11.Cu" signal "IN4")
		(26 "In12.Cu" signal "GND5")
		(28 "In13.Cu" signal "IN5")
		(30 "In14.Cu" signal "GND6")
		(32 "In15.Cu" signal "IN6")
		(34 "In16.Cu" signal "GND7")
		(2 "B.Cu" signal "BOTTOM")
		(9 "F.Adhes" user "F.Adhesive")
		(11 "B.Adhes" user "B.Adhesive")
		(13 "F.Paste" user "Package Geometry/Pastemask Top")
		(15 "B.Paste" user "Package Geometry/Pastemask Bottom")
		(5 "F.SilkS" user "Ref Des/Silkscreen Top")
		(7 "B.SilkS" user "Ref Des/Silkscreen Bottom")
		(1 "F.Mask" user "Board Geometry/Soldermask Top")
		(3 "B.Mask" user "Board Geometry/Soldermask Bottom")
		(17 "Dwgs.User" user "User.Drawings")
		(19 "Cmts.User" user "User.Comments")
		(21 "Eco1.User" user "User.Eco1")
		(23 "Eco2.User" user "User.Eco2")
		(25 "Edge.Cuts" user "Board Geometry/Outline")
		(27 "Margin" user)
		(31 "F.CrtYd" user "Package Geometry/Place Bound Top")
		(29 "B.CrtYd" user "Package Geometry/Place Bound Bottom")
		(35 "F.Fab" user "Ref Des/Assembly Top")
		(33 "B.Fab" user "Ref Des/Assembly Bottom")
	)
	(footprint ""
		(layer "F.Cu")
		(at 174.635922 -25.846532 180)
		(property "Reference" "PC2239"
			(at 0 0 180)
			(layer "F.SilkS")
			(hide yes)
			(effects
				(font
					(size 1.27 1.27)
				)
			)
		)
		(property "Value" ""
			(at 0 0 180)
			(layer "F.Fab")
			(effects
				(font
					(size 1.27 1.27)
				)
			)
		)
		(duplicate_pad_numbers_are_jumpers no)
		(fp_line
			(start 1.2954 0.5842)
			(end -1.2954 0.5842)
			(stroke
				(width 0.1524)
				(type default)
			)
			(layer "F.SilkS")
		)
		(fp_line
			(start 1.2954 -0.5842)
			(end 1.2954 0.5842)
			(stroke
				(width 0.1524)
				(type default)
			)
			(layer "F.SilkS")
		)
		(fp_line
			(start 0 -0.5842)
			(end 0 0.5842)
			(stroke
				(width 0.1524)
				(type default)
			)
			(layer "F.SilkS")
		)
		(fp_line
			(start -1.2954 0.5842)
			(end -1.2954 -0.5842)
			(stroke
				(width 0.1524)
				(type default)
			)
			(layer "F.SilkS")
		)
		(fp_line
			(start -1.2954 -0.5842)
			(end 1.2954 -0.5842)
			(stroke
				(width 0.1524)
				(type default)
			)
			(layer "F.SilkS")
		)
		(fp_line
			(start 1.1938 0.4064)
			(end 0.8636 0.4064)
			(stroke
				(width 0.1)
				(type default)
			)
			(layer "F.Fab")
		)
		(fp_line
			(start 1.1938 -0.4064)
			(end 1.1938 0.4064)
			(stroke
				(width 0.1)
				(type default)
			)
			(layer "F.Fab")
		)
		(fp_line
			(start 0.8636 0.4572)
			(end -0.8636 0.4572)
			(stroke
				(width 0.1)
				(type default)
			)
			(layer "F.Fab")
		)
		(fp_line
			(start 0.8636 0.4064)
			(end 0.8636 0.4572)
			(stroke
				(width 0.1)
				(type default)
			)
			(layer "F.Fab")
		)
		(fp_line
			(start 0.8636 -0.4064)
			(end 1.1938 -0.4064)
			(stroke
				(width 0.1)
				(type default)
			)
			(layer "F.Fab")
		)
		(fp_line
			(start 0.8636 -0.4572)
			(end 0.8636 -0.4064)
			(stroke
				(width 0.1)
				(type default)
			)
			(layer "F.Fab")
		)
		(fp_line
			(start -0.8636 0.4572)
			(end -0.8636 0.4064)
			(stroke
				(width 0.1)
				(type default)
			)
			(layer "F.Fab")
		)
		(fp_line
			(start -0.8636 0.4064)
			(end -1.1938 0.4064)
			(stroke
				(width 0.1)
				(type default)
			)
			(layer "F.Fab")
		)
		(fp_line
			(start -0.8636 -0.4064)
			(end -0.8636 -0.4572)
			(stroke
				(width 0.1)
				(type default)
			)
			(layer "F.Fab")
		)
		(fp_line
			(start -0.8636 -0.4572)
			(end 0.8636 -0.4572)
			(stroke
				(width 0.1)
				(type default)
			)
			(layer "F.Fab")
		)
		(fp_line
			(start -1.1938 0.4064)
			(end -1.1938 -0.4064)
			(stroke
				(width 0.1)
				(type default)
			)
			(layer "F.Fab")
		)
		(fp_line
			(start -1.1938 -0.4064)
			(end -0.8636 -0.4064)
			(stroke
				(width 0.1)
				(type default)
			)
			(layer "F.Fab")
		)
		(pad "1" smd rect
			(at -0.7366 0 90)
			(size 0.7112 0.8128)
			(layers "F.Cu" "F.Mask" "F.Paste")
			(net "P12V_SCM_AVIN_PD")
		)
		(pad "2" smd rect
			(at 0.7366 0 90)
			(size 0.7112 0.8128)
			(layers "F.Cu" "F.Mask" "F.Paste")
			(net "GND")
		)
	)
	(footprint ""
		(layer "F.Cu")
		(at 241.28857 -111.212376 180)
		(property "Reference" "R1018"
			(at 0 0 180)
			(layer "F.SilkS")
			(hide yes)
			(effects
				(font
					(size 1.27 1.27)
				)
			)
		)
		(property "Value" ""
			(at 0 0 180)
			(layer "F.Fab")
			(effects
				(font
					(size 1.27 1.27)
				)
			)
		)
		(duplicate_pad_numbers_are_jumpers no)
		(fp_line
			(start 0.7874 0.4064)
			(end -0.7874 0.4064)
			(stroke
				(width 0.1524)
				(type default)
			)
			(layer "F.SilkS")
		)
		(fp_line
			(start 0.7874 -0.4064)
			(end 0.7874 0.4064)
			(stroke
				(width 0.1524)
				(type default)
			)
			(layer "F.SilkS")
		)
		(fp_line
			(start -0.7874 0.4064)
			(end -0.7874 -0.4064)
			(stroke
				(width 0.1524)
				(type default)
			)
			(layer "F.SilkS")
		)
		(fp_line
			(start -0.7874 -0.4064)
			(end 0.7874 -0.4064)
			(stroke
				(width 0.1524)
				(type default)
			)
			(layer "F.SilkS")
		)
		(fp_line
			(start 0.67945 0.3048)
			(end 0.120396 0.3048)
			(stroke
				(width 0.1)
				(type default)
			)
			(layer "F.Fab")
		)
		(fp_line
			(start 0.67945 -0.3048)
			(end 0.67945 0.3048)
			(stroke
				(width 0.1)
				(type default)
			)
			(layer "F.Fab")
		)
		(fp_line
			(start 0.12065 -0.2794)
			(end 0.12065 -0.3048)
			(stroke
				(width 0.1)
				(type default)
			)
			(layer "F.Fab")
		)
		(fp_line
			(start 0.12065 -0.3048)
			(end 0.67945 -0.3048)
			(stroke
				(width 0.1)
				(type default)
			)
			(layer "F.Fab")
		)
		(fp_line
			(start 0.120396 0.3048)
			(end 0.120396 0.2794)
			(stroke
				(width 0.1)
				(type default)
			)
			(layer "F.Fab")
		)
		(fp_line
			(start 0.120396 0.2794)
			(end -0.12065 0.2794)
			(stroke
				(width 0.1)
				(type default)
			)
			(layer "F.Fab")
		)
		(fp_line
			(start -0.12065 0.3048)
			(end -0.67945 0.3048)
			(stroke
				(width 0.1)
				(type default)
			)
			(layer "F.Fab")
		)
		(fp_line
			(start -0.12065 0.2794)
			(end -0.12065 0.3048)
			(stroke
				(width 0.1)
				(type default)
			)
			(layer "F.Fab")
		)
		(fp_line
			(start -0.12065 -0.2794)
			(end 0.12065 -0.2794)
			(stroke
				(width 0.1)
				(type default)
			)
			(layer "F.Fab")
		)
		(fp_line
			(start -0.12065 -0.305054)
			(end -0.12065 -0.2794)
			(stroke
				(width 0.1)
				(type default)
			)
			(layer "F.Fab")
		)
		(fp_line
			(start -0.67945 0.3048)
			(end -0.67945 -0.305054)
			(stroke
				(width 0.1)
				(type default)
			)
			(layer "F.Fab")
		)
		(fp_line
			(start -0.67945 -0.305054)
			(end -0.12065 -0.305054)
			(stroke
				(width 0.1)
				(type default)
			)
			(layer "F.Fab")
		)
		(pad "1" smd circle
			(at -0.40005 0 180)
			(size 0 0)
			(layers "F.Cu" "F.Mask" "F.Paste")
			(net "CLK_25M_CK440_CPU1_DN")
		)
		(pad "2" smd circle
			(at 0.40005 0 180)
			(size 0 0)
			(layers "F.Cu" "F.Mask" "F.Paste")
			(net "CLK_25M_CK440_CPU1_R_DN")
		)
	)
)
